(kicad_pcb
	(version 20260206)
	(generator "pcbnew")
	(generator_version "10.0")
	(general
		(thickness 1.6)
		(legacy_teardrops no)
	)
	(paper "A4")
	(title_block
		(title "01162023_DA0F0TEBIF0_F0T_Expander_BD_F_brd_V02_OCP.brd")
		(comment 1 "Grand Teton / footprints 4016-4022 of 9728")
	)
	(layers
		(0 "F.Cu" signal "TOP")
		(4 "In1.Cu" signal "GND")
		(6 "In2.Cu" signal "VCC")
		(8 "In3.Cu" signal "VCC1")
		(10 "In4.Cu" signal "GND1")
		(12 "In5.Cu" signal "IN1")
		(14 "In6.Cu" signal "GND2")
		(16 "In7.Cu" signal "IN2")
		(18 "In8.Cu" signal "GND3")
		(20 "In9.Cu" signal "IN3")
		(22 "In10.Cu" signal "GND4")
		(24 "In11.Cu" signal "IN4")
		(26 "In12.Cu" signal "GND5")
		(28 "In13.Cu" signal "IN5")
		(30 "In14.Cu" signal "GND6")
		(32 "In15.Cu" signal "IN6")
		(34 "In16.Cu" signal "GND7")
		(2 "B.Cu" signal "BOTTOM")
		(9 "F.Adhes" user "F.Adhesive")
		(11 "B.Adhes" user "B.Adhesive")
		(13 "F.Paste" user "Package Geometry/Pastemask Top")
		(15 "B.Paste" user "Package Geometry/Pastemask Bottom")
		(5 "F.SilkS" user "Ref Des/Silkscreen Top")
		(7 "B.SilkS" user "Ref Des/Silkscreen Bottom")
		(1 "F.Mask" user "Board Geometry/Soldermask Top")
		(3 "B.Mask" user "Board Geometry/Soldermask Bottom")
		(17 "Dwgs.User" user "User.Drawings")
		(19 "Cmts.User" user "User.Comments")
		(21 "Eco1.User" user "User.Eco1")
		(23 "Eco2.User" user "User.Eco2")
		(25 "Edge.Cuts" user "Board Geometry/Outline")
		(27 "Margin" user)
		(31 "F.CrtYd" user "Package Geometry/Place Bound Top")
		(29 "B.CrtYd" user "Package Geometry/Place Bound Bottom")
		(35 "F.Fab" user "Ref Des/Assembly Top")
		(33 "B.Fab" user "Ref Des/Assembly Bottom")
	)
	(footprint ""
		(layer "F.Cu")
		(at 201.857864 -299.04055 -90)
		(property "Reference" "C4186"
			(at 0 0 270)
			(layer "F.SilkS")
			(hide yes)
			(effects
				(font
					(size 1.27 1.27)
				)
			)
		)
		(property "Value" ""
			(at 0 0 270)
			(layer "F.Fab")
			(effects
				(font
					(size 1.27 1.27)
				)
			)
		)
		(duplicate_pad_numbers_are_jumpers no)
		(fp_line
			(start -0.7874 0.4064)
			(end -0.7874 -0.4064)
			(stroke
				(width 0.1524)
				(type default)
			)
			(layer "F.SilkS")
		)
		(fp_line
			(start 0.7874 0.4064)
			(end -0.7874 0.4064)
			(stroke
				(width 0.1524)
				(type default)
			)
			(layer "F.SilkS")
		)
		(fp_line
			(start -0.7874 -0.4064)
			(end 0.7874 -0.4064)
			(stroke
				(width 0.1524)
				(type default)
			)
			(layer "F.SilkS")
		)
		(fp_line
			(start 0.7874 -0.4064)
			(end 0.7874 0.4064)
			(stroke
				(width 0.1524)
				(type default)
			)
			(layer "F.SilkS")
		)
		(fp_line
			(start -0.67945 0.3048)
			(end -0.67945 -0.305054)
			(stroke
				(width 0.1)
				(type default)
			)
			(layer "F.Fab")
		)
		(fp_line
			(start -0.12065 0.3048)
			(end -0.67945 0.3048)
			(stroke
				(width 0.1)
				(type default)
			)
			(layer "F.Fab")
		)
		(fp_line
			(start 0.120396 0.3048)
			(end 0.120396 0.2794)
			(stroke
				(width 0.1)
				(type default)
			)
			(layer "F.Fab")
		)
		(fp_line
			(start 0.67945 0.3048)
			(end 0.120396 0.3048)
			(stroke
				(width 0.1)
				(type default)
			)
			(layer "F.Fab")
		)
		(fp_line
			(start -0.12065 0.2794)
			(end -0.12065 0.3048)
			(stroke
				(width 0.1)
				(type default)
			)
			(layer "F.Fab")
		)
		(fp_line
			(start 0.120396 0.2794)
			(end -0.12065 0.2794)
			(stroke
				(width 0.1)
				(type default)
			)
			(layer "F.Fab")
		)
		(fp_line
			(start -0.12065 -0.2794)
			(end 0.12065 -0.2794)
			(stroke
				(width 0.1)
				(type default)
			)
			(layer "F.Fab")
		)
		(fp_line
			(start 0.12065 -0.2794)
			(end 0.12065 -0.3048)
			(stroke
				(width 0.1)
				(type default)
			)
			(layer "F.Fab")
		)
		(fp_line
			(start 0.12065 -0.3048)
			(end 0.67945 -0.3048)
			(stroke
				(width 0.1)
				(type default)
			)
			(layer "F.Fab")
		)
		(fp_line
			(start 0.67945 -0.3048)
			(end 0.67945 0.3048)
			(stroke
				(width 0.1)
				(type default)
			)
			(layer "F.Fab")
		)
		(fp_line
			(start -0.67945 -0.305054)
			(end -0.12065 -0.305054)
			(stroke
				(width 0.1)
				(type default)
			)
			(layer "F.Fab")
		)
		(fp_line
			(start -0.12065 -0.305054)
			(end -0.12065 -0.2794)
			(stroke
				(width 0.1)
				(type default)
			)
			(layer "F.Fab")
		)
		(pad "1" smd circle
			(at -0.40005 0 270)
			(size 0 0)
			(layers "F.Cu" "F.Mask" "F.Paste")
			(net "GND")
		)
		(pad "2" smd circle
			(at 0.40005 0 270)
			(size 0 0)
			(layers "F.Cu" "F.Mask" "F.Paste")
			(net "P1V8_PEX")
		)
	)
	(footprint ""
		(layer "F.Cu")
		(at 319.913 -85.344 180)
		(property "Reference" "R6258"
			(at 0 0 180)
			(layer "F.SilkS")
			(hide yes)
			(effects
				(font
					(size 1.27 1.27)
				)
			)
		)
		(property "Value" ""
			(at 0 0 180)
			(layer "F.Fab")
			(effects
				(font
					(size 1.27 1.27)
				)
			)
		)
		(duplicate_pad_numbers_are_jumpers no)
		(fp_line
			(start 0.7874 0.4064)
			(end -0.7874 0.4064)
			(stroke
				(width 0.1524)
				(type default)
			)
			(layer "F.SilkS")
		)
		(fp_line
			(start 0.7874 -0.4064)
			(end 0.7874 0.4064)
			(stroke
				(width 0.1524)
				(type default)
			)
			(layer "F.SilkS")
		)
		(fp_line
			(start -0.7874 0.4064)
			(end -0.7874 -0.4064)
			(stroke
				(width 0.1524)
				(type default)
			)
			(layer "F.SilkS")
		)
		(fp_line
			(start -0.7874 -0.4064)
			(end 0.7874 -0.4064)
			(stroke
				(width 0.1524)
				(type default)
			)
			(layer "F.SilkS")
		)
		(fp_line
			(start 0.67945 0.3048)
			(end 0.120396 0.3048)
			(stroke
				(width 0.1)
				(type default)
			)
			(layer "F.Fab")
		)
		(fp_line
			(start 0.67945 -0.3048)
			(end 0.67945 0.3048)
			(stroke
				(width 0.1)
				(type default)
			)
			(layer "F.Fab")
		)
		(fp_line
			(start 0.12065 -0.2794)
			(end 0.12065 -0.3048)
			(stroke
				(width 0.1)
				(type default)
			)
			(layer "F.Fab")
		)
		(fp_line
			(start 0.12065 -0.3048)
			(end 0.67945 -0.3048)
			(stroke
				(width 0.1)
				(type default)
			)
			(layer "F.Fab")
		)
		(fp_line
			(start 0.120396 0.3048)
			(end 0.120396 0.2794)
			(stroke
				(width 0.1)
				(type default)
			)
			(layer "F.Fab")
		)
		(fp_line
			(start 0.120396 0.2794)
			(end -0.12065 0.2794)
			(stroke
				(width 0.1)
				(type default)
			)
			(layer "F.Fab")
		)
		(fp_line
			(start -0.12065 0.3048)
			(end -0.67945 0.3048)
			(stroke
				(width 0.1)
				(type default)
			)
			(layer "F.Fab")
		)
		(fp_line
			(start -0.12065 0.2794)
			(end -0.12065 0.3048)
			(stroke
				(width 0.1)
				(type default)
			)
			(layer "F.Fab")
		)
		(fp_line
			(start -0.12065 -0.2794)
			(end 0.12065 -0.2794)
			(stroke
				(width 0.1)
				(type default)
			)
			(layer "F.Fab")
		)
		(fp_line
			(start -0.12065 -0.305054)
			(end -0.12065 -0.2794)
			(stroke
				(width 0.1)
				(type default)
			)
			(layer "F.Fab")
		)
		(fp_line
			(start -0.67945 0.3048)
			(end -0.67945 -0.305054)
			(stroke
				(width 0.1)
				(type default)
			)
			(layer "F.Fab")
		)
		(fp_line
			(start -0.67945 -0.305054)
			(end -0.12065 -0.305054)
			(stroke
				(width 0.1)
				(type default)
			)
			(layer "F.Fab")
		)
		(pad "1" smd circle
			(at -0.40005 0 180)
			(size 0 0)
			(layers "F.Cu" "F.Mask" "F.Paste")
			(net "CB_ISO_EN")
		)
		(pad "2" smd circle
			(at 0.40005 0 180)
			(size 0 0)
			(layers "F.Cu" "F.Mask" "F.Paste")
			(net "P3V3_AUX")
		)
	)
	(footprint ""
		(layer "F.Cu")
		(at 220.34373 -49.95291 180)
		(property "Reference" "R588"
			(at 0 0 180)
			(layer "F.SilkS")
			(hide yes)
			(effects
				(font
					(size 1.27 1.27)
				)
			)
		)
		(property "Value" ""
			(at 0 0 180)
			(layer "F.Fab")
			(effects
				(font
					(size 1.27 1.27)
				)
			)
		)
		(duplicate_pad_numbers_are_jumpers no)
		(fp_line
			(start 0.7874 0.4064)
			(end -0.7874 0.4064)
			(stroke
				(width 0.1524)
				(type default)
			)
			(layer "F.SilkS")
		)
		(fp_line
			(start 0.7874 -0.4064)
			(end 0.7874 0.4064)
			(stroke
				(width 0.1524)
				(type default)
			)
			(layer "F.SilkS")
		)
		(fp_line
			(start -0.7874 0.4064)
			(end -0.7874 -0.4064)
			(stroke
				(width 0.1524)
				(type default)
			)
			(layer "F.SilkS")
		)
		(fp_line
			(start -0.7874 -0.4064)
			(end 0.7874 -0.4064)
			(stroke
				(width 0.1524)
				(type default)
			)
			(layer "F.SilkS")
		)
		(fp_line
			(start 0.67945 0.3048)
			(end 0.120396 0.3048)
			(stroke
				(width 0.1)
				(type default)
			)
			(layer "F.Fab")
		)
		(fp_line
			(start 0.67945 -0.3048)
			(end 0.67945 0.3048)
			(stroke
				(width 0.1)
				(type default)
			)
			(layer "F.Fab")
		)
		(fp_line
			(start 0.12065 -0.2794)
			(end 0.12065 -0.3048)
			(stroke
				(width 0.1)
				(type default)
			)
			(layer "F.Fab")
		)
		(fp_line
			(start 0.12065 -0.3048)
			(end 0.67945 -0.3048)
			(stroke
				(width 0.1)
				(type default)
			)
			(layer "F.Fab")
		)
		(fp_line
			(start 0.120396 0.3048)
			(end 0.120396 0.2794)
			(stroke
				(width 0.1)
				(type default)
			)
			(layer "F.Fab")
		)
		(fp_line
			(start 0.120396 0.2794)
			(end -0.12065 0.2794)
			(stroke
				(width 0.1)
				(type default)
			)
			(layer "F.Fab")
		)
		(fp_line
			(start -0.12065 0.3048)
			(end -0.67945 0.3048)
			(stroke
				(width 0.1)
				(type default)
			)
			(layer "F.Fab")
		)
		(fp_line
			(start -0.12065 0.2794)
			(end -0.12065 0.3048)
			(stroke
				(width 0.1)
				(type default)
			)
			(layer "F.Fab")
		)
		(fp_line
			(start -0.12065 -0.2794)
			(end 0.12065 -0.2794)
			(stroke
				(width 0.1)
				(type default)
			)
			(layer "F.Fab")
		)
		(fp_line
			(start -0.12065 -0.305054)
			(end -0.12065 -0.2794)
			(stroke
				(width 0.1)
				(type default)
			)
			(layer "F.Fab")
		)
		(fp_line
			(start -0.67945 0.3048)
			(end -0.67945 -0.305054)
			(stroke
				(width 0.1)
				(type default)
			)
			(layer "F.Fab")
		)
		(fp_line
			(start -0.67945 -0.305054)
			(end -0.12065 -0.305054)
			(stroke
				(width 0.1)
				(type default)
			)
			(layer "F.Fab")
		)
		(pad "1" smd circle
			(at -0.40005 0 180)
			(size 0 0)
			(layers "F.Cu" "F.Mask" "F.Paste")
			(net "SMB_BIC_I2C6_MUX_SSD_0_7_ADC_R_SCL")
		)
		(pad "2" smd circle
			(at 0.40005 0 180)
			(size 0 0)
			(layers "F.Cu" "F.Mask" "F.Paste")
			(net "SMB_SSD7_ADC_SCL")
		)
	)
	(footprint ""
		(layer "F.Cu")
		(at 409.015438 -85.408008 180)
		(property "Reference" "C3995"
			(at 0 0 180)
			(layer "F.SilkS")
			(hide yes)
			(effects
				(font
					(size 1.27 1.27)
				)
			)
		)
		(property "Value" ""
			(at 0 0 180)
			(layer "F.Fab")
			(effects
				(font
					(size 1.27 1.27)
				)
			)
		)
		(duplicate_pad_numbers_are_jumpers no)
		(fp_line
			(start 0.7874 0.4064)
			(end -0.7874 0.4064)
			(stroke
				(width 0.1524)
				(type default)
			)
			(layer "F.SilkS")
		)
		(fp_line
			(start 0.7874 -0.4064)
			(end 0.7874 0.4064)
			(stroke
				(width 0.1524)
				(type default)
			)
			(layer "F.SilkS")
		)
		(fp_line
			(start -0.7874 0.4064)
			(end -0.7874 -0.4064)
			(stroke
				(width 0.1524)
				(type default)
			)
			(layer "F.SilkS")
		)
		(fp_line
			(start -0.7874 -0.4064)
			(end 0.7874 -0.4064)
			(stroke
				(width 0.1524)
				(type default)
			)
			(layer "F.SilkS")
		)
		(fp_line
			(start 0.67945 0.3048)
			(end 0.120396 0.3048)
			(stroke
				(width 0.1)
				(type default)
			)
			(layer "F.Fab")
		)
		(fp_line
			(start 0.67945 -0.3048)
			(end 0.67945 0.3048)
			(stroke
				(width 0.1)
				(type default)
			)
			(layer "F.Fab")
		)
		(fp_line
			(start 0.12065 -0.2794)
			(end 0.12065 -0.3048)
			(stroke
				(width 0.1)
				(type default)
			)
			(layer "F.Fab")
		)
		(fp_line
			(start 0.12065 -0.3048)
			(end 0.67945 -0.3048)
			(stroke
				(width 0.1)
				(type default)
			)
			(layer "F.Fab")
		)
		(fp_line
			(start 0.120396 0.3048)
			(end 0.120396 0.2794)
			(stroke
				(width 0.1)
				(type default)
			)
			(layer "F.Fab")
		)
		(fp_line
			(start 0.120396 0.2794)
			(end -0.12065 0.2794)
			(stroke
				(width 0.1)
				(type default)
			)
			(layer "F.Fab")
		)
		(fp_line
			(start -0.12065 0.3048)
			(end -0.67945 0.3048)
			(stroke
				(width 0.1)
				(type default)
			)
			(layer "F.Fab")
		)
		(fp_line
			(start -0.12065 0.2794)
			(end -0.12065 0.3048)
			(stroke
				(width 0.1)
				(type default)
			)
			(layer "F.Fab")
		)
		(fp_line
			(start -0.12065 -0.2794)
			(end 0.12065 -0.2794)
			(stroke
				(width 0.1)
				(type default)
			)
			(layer "F.Fab")
		)
		(fp_line
			(start -0.12065 -0.305054)
			(end -0.12065 -0.2794)
			(stroke
				(width 0.1)
				(type default)
			)
			(layer "F.Fab")
		)
		(fp_line
			(start -0.67945 0.3048)
			(end -0.67945 -0.305054)
			(stroke
				(width 0.1)
				(type default)
			)
			(layer "F.Fab")
		)
		(fp_line
			(start -0.67945 -0.305054)
			(end -0.12065 -0.305054)
			(stroke
				(width 0.1)
				(type default)
			)
			(layer "F.Fab")
		)
		(pad "1" smd circle
			(at -0.40005 0 180)
			(size 0 0)
			(layers "F.Cu" "F.Mask" "F.Paste")
			(net "GND")
		)
		(pad "2" smd circle
			(at 0.40005 0 180)
			(size 0 0)
			(layers "F.Cu" "F.Mask" "F.Paste")
			(net "P3V3")
		)
	)
	(footprint ""
		(layer "F.Cu")
		(at 295.877742 -115.283742 180)
		(property "Reference" "R292"
			(at 0 0 180)
			(layer "F.SilkS")
			(hide yes)
			(effects
				(font
					(size 1.27 1.27)
				)
			)
		)
		(property "Value" ""
			(at 0 0 180)
			(layer "F.Fab")
			(effects
				(font
					(size 1.27 1.27)
				)
			)
		)
		(duplicate_pad_numbers_are_jumpers no)
		(fp_line
			(start 0.7874 0.4064)
			(end -0.7874 0.4064)
			(stroke
				(width 0.1524)
				(type default)
			)
			(layer "F.SilkS")
		)
		(fp_line
			(start 0.7874 -0.4064)
			(end 0.7874 0.4064)
			(stroke
				(width 0.1524)
				(type default)
			)
			(layer "F.SilkS")
		)
		(fp_line
			(start -0.7874 0.4064)
			(end -0.7874 -0.4064)
			(stroke
				(width 0.1524)
				(type default)
			)
			(layer "F.SilkS")
		)
		(fp_line
			(start -0.7874 -0.4064)
			(end 0.7874 -0.4064)
			(stroke
				(width 0.1524)
				(type default)
			)
			(layer "F.SilkS")
		)
		(fp_line
			(start 0.67945 0.3048)
			(end 0.120396 0.3048)
			(stroke
				(width 0.1)
				(type default)
			)
			(layer "F.Fab")
		)
		(fp_line
			(start 0.67945 -0.3048)
			(end 0.67945 0.3048)
			(stroke
				(width 0.1)
				(type default)
			)
			(layer "F.Fab")
		)
		(fp_line
			(start 0.12065 -0.2794)
			(end 0.12065 -0.3048)
			(stroke
				(width 0.1)
				(type default)
			)
			(layer "F.Fab")
		)
		(fp_line
			(start 0.12065 -0.3048)
			(end 0.67945 -0.3048)
			(stroke
				(width 0.1)
				(type default)
			)
			(layer "F.Fab")
		)
		(fp_line
			(start 0.120396 0.3048)
			(end 0.120396 0.2794)
			(stroke
				(width 0.1)
				(type default)
			)
			(layer "F.Fab")
		)
		(fp_line
			(start 0.120396 0.2794)
			(end -0.12065 0.2794)
			(stroke
				(width 0.1)
				(type default)
			)
			(layer "F.Fab")
		)
		(fp_line
			(start -0.12065 0.3048)
			(end -0.67945 0.3048)
			(stroke
				(width 0.1)
				(type default)
			)
			(layer "F.Fab")
		)
		(fp_line
			(start -0.12065 0.2794)
			(end -0.12065 0.3048)
			(stroke
				(width 0.1)
				(type default)
			)
			(layer "F.Fab")
		)
		(fp_line
			(start -0.12065 -0.2794)
			(end 0.12065 -0.2794)
			(stroke
				(width 0.1)
				(type default)
			)
			(layer "F.Fab")
		)
		(fp_line
			(start -0.12065 -0.305054)
			(end -0.12065 -0.2794)
			(stroke
				(width 0.1)
				(type default)
			)
			(layer "F.Fab")
		)
		(fp_line
			(start -0.67945 0.3048)
			(end -0.67945 -0.305054)
			(stroke
				(width 0.1)
				(type default)
			)
			(layer "F.Fab")
		)
		(fp_line
			(start -0.67945 -0.305054)
			(end -0.12065 -0.305054)
			(stroke
				(width 0.1)
				(type default)
			)
			(layer "F.Fab")
		)
		(pad "1" smd circle
			(at -0.40005 0 180)
			(size 0 0)
			(layers "F.Cu" "F.Mask" "F.Paste")
			(net "RST_SMB_NIC5_MUX_ISO_R_N")
		)
		(pad "2" smd circle
			(at 0.40005 0 180)
			(size 0 0)
			(layers "F.Cu" "F.Mask" "F.Paste")
			(net "RST_SMB_NIC5_MUX_ISO_N")
		)
	)
	(footprint ""
		(layer "F.Cu")
		(at 17.326102 -266.899136)
		(property "Reference" "C4225"
			(at 0 0 0)
			(layer "F.SilkS")
			(hide yes)
			(effects
				(font
					(size 1.27 1.27)
				)
			)
		)
		(property "Value" ""
			(at 0 0 0)
			(layer "F.Fab")
			(effects
				(font
					(size 1.27 1.27)
				)
			)
		)
		(duplicate_pad_numbers_are_jumpers no)
		(fp_line
			(start -0.299974 -0.150114)
			(end 0.299974 -0.150114)
			(stroke
				(width 0.1)
				(type default)
			)
			(layer "F.Fab")
		)
		(fp_line
			(start -0.299974 0.150114)
			(end -0.299974 -0.150114)
			(stroke
				(width 0.1)
				(type default)
			)
			(layer "F.Fab")
		)
		(fp_line
			(start 0.299974 -0.150114)
			(end 0.299974 0.150114)
			(stroke
				(width 0.1)
				(type default)
			)
			(layer "F.Fab")
		)
		(fp_line
			(start 0.299974 0.150114)
			(end -0.299974 0.150114)
			(stroke
				(width 0.1)
				(type default)
			)
			(layer "F.Fab")
		)
		(pad "1" smd rect
			(at -0.2667 0)
			(size 0.3048 0.381)
			(layers "F.Cu" "F.Mask" "F.Paste")
			(net "P1V25_SERDES_VDDPLL_PEX0")
		)
		(pad "2" smd rect
			(at 0.2667 0)
			(size 0.3048 0.381)
			(layers "F.Cu" "F.Mask" "F.Paste")
			(net "GND")
		)
	)
	(footprint ""
		(layer "F.Cu")
		(at 138.920728 -70.307454 90)
		(property "Reference" "PC839"
			(at 0 0 90)
			(layer "F.SilkS")
			(hide yes)
			(effects
				(font
					(size 1.27 1.27)
				)
			)
		)
		(property "Value" ""
			(at 0 0 90)
			(layer "F.Fab")
			(effects
				(font
					(size 1.27 1.27)
				)
			)
		)
		(duplicate_pad_numbers_are_jumpers no)
		(fp_line
			(start 0.7874 -0.4064)
			(end 0.7874 0.4064)
			(stroke
				(width 0.1524)
				(type default)
			)
			(layer "F.SilkS")
		)
		(fp_line
			(start -0.7874 -0.4064)
			(end 0.7874 -0.4064)
			(stroke
				(width 0.1524)
				(type default)
			)
			(layer "F.SilkS")
		)
		(fp_line
			(start 0.7874 0.4064)
			(end -0.7874 0.4064)
			(stroke
				(width 0.1524)
				(type default)
			)
			(layer "F.SilkS")
		)
		(fp_line
			(start -0.7874 0.4064)
			(end -0.7874 -0.4064)
			(stroke
				(width 0.1524)
				(type default)
			)
			(layer "F.SilkS")
		)
		(fp_line
			(start -0.12065 -0.305054)
			(end -0.12065 -0.2794)
			(stroke
				(width 0.1)
				(type default)
			)
			(layer "F.Fab")
		)
		(fp_line
			(start -0.67945 -0.305054)
			(end -0.12065 -0.305054)
			(stroke
				(width 0.1)
				(type default)
			)
			(layer "F.Fab")
		)
		(fp_line
			(start 0.67945 -0.3048)
			(end 0.67945 0.3048)
			(stroke
				(width 0.1)
				(type default)
			)
			(layer "F.Fab")
		)
		(fp_line
			(start 0.12065 -0.3048)
			(end 0.67945 -0.3048)
			(stroke
				(width 0.1)
				(type default)
			)
			(layer "F.Fab")
		)
		(fp_line
			(start 0.12065 -0.2794)
			(end 0.12065 -0.3048)
			(stroke
				(width 0.1)
				(type default)
			)
			(layer "F.Fab")
		)
		(fp_line
			(start -0.12065 -0.2794)
			(end 0.12065 -0.2794)
			(stroke
				(width 0.1)
				(type default)
			)
			(layer "F.Fab")
		)
		(fp_line
			(start 0.120396 0.2794)
			(end -0.12065 0.2794)
			(stroke
				(width 0.1)
				(type default)
			)
			(layer "F.Fab")
		)
		(fp_line
			(start -0.12065 0.2794)
			(end -0.12065 0.3048)
			(stroke
				(width 0.1)
				(type default)
			)
			(layer "F.Fab")
		)
		(fp_line
			(start 0.67945 0.3048)
			(end 0.120396 0.3048)
			(stroke
				(width 0.1)
				(type default)
			)
			(layer "F.Fab")
		)
		(fp_line
			(start 0.120396 0.3048)
			(end 0.120396 0.2794)
			(stroke
				(width 0.1)
				(type default)
			)
			(layer "F.Fab")
		)
		(fp_line
			(start -0.12065 0.3048)
			(end -0.67945 0.3048)
			(stroke
				(width 0.1)
				(type default)
			)
			(layer "F.Fab")
		)
		(fp_line
			(start -0.67945 0.3048)
			(end -0.67945 -0.305054)
			(stroke
				(width 0.1)
				(type default)
			)
			(layer "F.Fab")
		)
		(pad "1" smd circle
			(at -0.40005 0 90)
			(size 0 0)
			(layers "F.Cu" "F.Mask" "F.Paste")
			(net "P12V_AUX")
		)
		(pad "2" smd circle
			(at 0.40005 0 90)
			(size 0 0)
			(layers "F.Cu" "F.Mask" "F.Paste")
			(net "GND")
		)
	)
)
